#ISCELL
  mstr_misc dns *
  *
#ISCELL
  pure_quanta quanta_title_block_c *
  *
#ISCELL
  pure_quanta_power cad_note *
  *
#ISCELL
  pure_quanta_power universal_gnd *
  page338_i1
#ISCELL
  pure_quanta_power universal_power *
  page338_i10
#CELL
  pure_quanta q_cap *
  page338_i100
#CELL
  pure_quanta q_res *
  page338_i101
#ISCELL
  pure_quanta_power vccaux15 *
  page338_i102
#CELL
  pure_quanta q_cap *
  page338_i104
#ISCELL
  pure_quanta_power gnd *
  page338_i105
#CELL
  pure_quanta q_cap *
  page338_i106
#ISCELL
  pure_quanta_power universal_power *
  page338_i107
#ISCELL
  standard offpage *
  page338_i108
#ISCELL
  pure_quanta_power gnd *
  page338_i109
#CELL
  pure_quanta mosfet_nch_dual *
  page338_i11
#CELL
  pure_quanta q_cap *
  page338_i110
#CELL
  pure_quanta q_res *
  page338_i111
#CELL
  pure_quanta mosfet_nch_dual *
  page338_i112
#CELL
  pure_quanta max15090bewit *
  page338_i113
#CELL
  pure_quanta q_res *
  page338_i114
#CELL
  pure_quanta diode_tvs *
  page338_i115
#CELL
  pure_quanta q_res *
  page338_i116
#ISCELL
  standard offpage *
  page338_i117
#CELL
  pure_quanta q_res *
  page338_i118
#ISCELL
  pure_quanta_power gnd *
  page338_i12
#CELL
  pure_quanta q_res *
  page338_i123
#ISCELL
  standard offpage *
  page338_i124
#CELL
  pure_quanta q_res *
  page338_i125
#CELL
  pure_quanta q_res *
  page338_i126
#CELL
  pure_quanta q_res *
  page338_i127
#ISCELL
  standard offpage *
  page338_i129
#ISCELL
  standard offpage *
  page338_i13
#CELL
  pure_quanta q_res *
  page338_i130
#CELL
  pure_quanta q_res *
  page338_i131
#CELL
  pure_quanta q_res *
  page338_i132
#CELL
  pure_quanta q_res *
  page338_i133
#ISCELL
  standard offpage *
  page338_i134
#CELL
  pure_quanta q_res *
  page338_i135
#ISCELL
  standard offpage *
  page338_i14
#CELL
  pure_quanta q_res *
  page338_i15
#ISCELL
  pure_quanta_power universal_power *
  page338_i16
#CELL
  pure_quanta q_res *
  page338_i17
#ISCELL
  pure_quanta_power universal_power *
  page338_i18
#CELL
  pure_quanta mosfet_nch_dual *
  page338_i19
#ISCELL
  standard offpage *
  page338_i2
#ISCELL
  pure_quanta_power gnd *
  page338_i20
#CELL
  pure_quanta mosfet_nch_dual *
  page338_i23
#CELL
  pure_quanta q_res *
  page338_i24
#ISCELL
  pure_quanta_power universal_gnd *
  page338_i25
#CELL
  pure_quanta 74lvc2g07dw7 *
  page338_i26
#ISCELL
  pure_quanta_power universal_gnd *
  page338_i27
#CELL
  pure_quanta q_res *
  page338_i28
#CELL
  pure_quanta 74lvc2g07dw7 *
  page338_i29
#ISCELL
  standard offpage *
  page338_i3
#CELL
  pure_quanta q_cap *
  page338_i30
#ISCELL
  pure_quanta_power universal_power *
  page338_i31
#ISCELL
  pure_quanta_power universal_gnd *
  page338_i32
#CELL
  pure_quanta q_cap *
  page338_i33
#ISCELL
  pure_quanta_power universal_power *
  page338_i34
#ISCELL
  pure_quanta_power gnd *
  page338_i35
#CELL
  pure_quanta q_res *
  page338_i36
#ISCELL
  pure_quanta_power gnd *
  page338_i37
#ISCELL
  pure_quanta_power gnd *
  page338_i38
#ISCELL
  pure_quanta_power gnd *
  page338_i39
#CELL
  pure_quanta q_res *
  page338_i40
#ISCELL
  pure_quanta_power gnd *
  page338_i41
#CELL
  pure_quanta q_res *
  page338_i42
#CELL
  pure_quanta q_res *
  page338_i43
#ISCELL
  pure_quanta_power universal_power *
  page338_i44
#CELL
  pure_quanta q_cap *
  page338_i45
#CELL
  pure_quanta q_res *
  page338_i46
#CELL
  pure_quanta q_res *
  page338_i48
#ISCELL
  pure_quanta_power gnd *
  page338_i49
#ISCELL
  pure_quanta_power gnd *
  page338_i5
#CELL
  pure_quanta max15090bewit *
  page338_i50
#ISCELL
  pure_quanta_power universal_power *
  page338_i52
#ISCELL
  pure_quanta_power gnd *
  page338_i53
#CELL
  pure_quanta q_cap *
  page338_i54
#CELL
  pure_quanta q_cap *
  page338_i55
#CELL
  pure_quanta q_res *
  page338_i56
#ISCELL
  pure_quanta_power gnd *
  page338_i57
#ISCELL
  pure_quanta_power gnd *
  page338_i58
#CELL
  pure_quanta q_res *
  page338_i59
#ISCELL
  pure_quanta_power universal_power *
  page338_i60
#CELL
  pure_quanta q_res *
  page338_i61
#CELL
  pure_quanta q_cap *
  page338_i62
#ISCELL
  pure_quanta_power universal_power *
  page338_i63
#CELL
  pure_quanta q_res *
  page338_i64
#ISCELL
  pure_quanta_power gnd *
  page338_i65
#CELL
  pure_quanta q_res *
  page338_i66
#CELL
  pure_quanta q_cap *
  page338_i67
#CELL
  pure_quanta q_res *
  page338_i68
#ISCELL
  standard offpage *
  page338_i69
#ISCELL
  standard offpage *
  page338_i7
#CELL
  pure_quanta q_res *
  page338_i71
#ISCELL
  pure_quanta_power gnd *
  page338_i72
#CELL
  pure_quanta q_res *
  page338_i73
#CELL
  pure_quanta q_cap *
  page338_i74
#CELL
  pure_quanta q_res *
  page338_i75
#CELL
  pure_quanta q_res *
  page338_i76
#CELL
  pure_quanta q_cap *
  page338_i77
#ISCELL
  pure_quanta_power gnd *
  page338_i78
#CELL
  pure_quanta schottky_ac *
  page338_i79
#ISCELL
  standard offpage *
  page338_i8
#CELL
  pure_quanta q_res *
  page338_i80
#ISCELL
  pure_quanta_power gnd *
  page338_i81
#CELL
  pure_quanta q_res *
  page338_i82
#CELL
  pure_quanta q_res *
  page338_i83
#ISCELL
  pure_quanta_power vccaux15 *
  page338_i84
#CELL
  pure_quanta q_res *
  page338_i85
#CELL
  pure_quanta q_cap *
  page338_i86
#CELL
  pure_quanta q_cap *
  page338_i87
#ISCELL
  pure_quanta_power gnd *
  page338_i88
#CELL
  pure_quanta q_cap *
  page338_i89
#CELL
  pure_quanta q_res *
  page338_i9
#ISCELL
  pure_quanta_power universal_power *
  page338_i90
#ISCELL
  standard offpage *
  page338_i91
#ISCELL
  standard offpage *
  page338_i92
#ISCELL
  standard offpage *
  page338_i93
#CELL
  pure_quanta q_cap *
  page338_i94
#CELL
  pure_quanta q_res *
  page338_i95
#CELL
  pure_quanta q_res *
  page338_i96
#CELL
  pure_quanta schottky_ac *
  page338_i97
#ISCELL
  pure_quanta_power gnd *
  page338_i99
